#ISCELL
  mstr_symbols bom_note *
  *
#ISCELL
  mstr_symbols intel_corp_bpage *
  *
#ISCELL
  mstr_standard offpage *
  page47_i1
#ISCELL
  mstr_standard tap *
  page47_i10
#ISCELL
  mstr_standard tap *
  page47_i100
#ISCELL
  mstr_standard tap *
  page47_i101
#ISCELL
  mstr_standard tap *
  page47_i102
#ISCELL
  mstr_standard tap *
  page47_i103
#ISCELL
  mstr_standard tap *
  page47_i104
#ISCELL
  mstr_standard tap *
  page47_i105
#ISCELL
  mstr_standard tap *
  page47_i106
#ISCELL
  mstr_standard tap *
  page47_i107
#ISCELL
  mstr_standard tap *
  page47_i108
#ISCELL
  mstr_standard tap *
  page47_i109
#ISCELL
  mstr_standard tap *
  page47_i110
#CELL
  mstr_sconn sconn288_h44441004 *
  page47_i111
#ISCELL
  mstr_standard tap *
  page47_i112
#ISCELL
  mstr_standard tap *
  page47_i113
#ISCELL
  mstr_standard tap *
  page47_i114
#ISCELL
  mstr_standard tap *
  page47_i115
#ISCELL
  mstr_standard tap *
  page47_i116
#ISCELL
  mstr_standard tap *
  page47_i117
#ISCELL
  mstr_standard tap *
  page47_i118
#ISCELL
  mstr_standard tap *
  page47_i119
#ISCELL
  mstr_symbols pvtt_abc *
  page47_i12
#ISCELL
  mstr_standard tap *
  page47_i120
#ISCELL
  mstr_standard tap *
  page47_i121
#ISCELL
  mstr_standard tap *
  page47_i122
#ISCELL
  mstr_standard tap *
  page47_i123
#ISCELL
  mstr_standard tap *
  page47_i124
#ISCELL
  mstr_standard tap *
  page47_i125
#ISCELL
  mstr_standard tap *
  page47_i126
#ISCELL
  mstr_standard offpage *
  page47_i127
#ISCELL
  mstr_standard tap *
  page47_i128
#ISCELL
  mstr_standard tap *
  page47_i129
#ISCELL
  mstr_symbols pvddq_abc *
  page47_i13
#ISCELL
  mstr_standard tap *
  page47_i130
#ISCELL
  mstr_standard tap *
  page47_i131
#ISCELL
  mstr_standard tap *
  page47_i132
#ISCELL
  mstr_standard tap *
  page47_i133
#ISCELL
  mstr_standard tap *
  page47_i134
#ISCELL
  mstr_standard offpage *
  page47_i135
#ISCELL
  mstr_standard offpage *
  page47_i136
#ISCELL
  mstr_standard offpage *
  page47_i137
#ISCELL
  mstr_standard tap *
  page47_i138
#ISCELL
  mstr_standard tap *
  page47_i139
#ISCELL
  mstr_standard tap *
  page47_i14
#ISCELL
  mstr_standard tap *
  page47_i140
#ISCELL
  mstr_standard tap *
  page47_i141
#ISCELL
  mstr_standard tap *
  page47_i142
#ISCELL
  mstr_standard tap *
  page47_i143
#ISCELL
  mstr_standard tap *
  page47_i144
#ISCELL
  mstr_standard tap *
  page47_i145
#ISCELL
  mstr_standard offpage *
  page47_i146
#ISCELL
  mstr_standard offpage *
  page47_i147
#ISCELL
  mstr_standard offpage *
  page47_i148
#ISCELL
  mstr_standard offpage *
  page47_i149
#ISCELL
  mstr_standard tap *
  page47_i15
#ISCELL
  mstr_standard offpage *
  page47_i150
#ISCELL
  mstr_standard offpage *
  page47_i151
#ISCELL
  mstr_standard tap *
  page47_i152
#ISCELL
  mstr_standard tap *
  page47_i153
#ISCELL
  mstr_standard offpage *
  page47_i154
#ISCELL
  mstr_standard tap *
  page47_i155
#ISCELL
  mstr_standard tap *
  page47_i156
#ISCELL
  mstr_standard offpage *
  page47_i157
#ISCELL
  mstr_standard tap *
  page47_i158
#ISCELL
  mstr_standard offpage *
  page47_i159
#ISCELL
  mstr_standard tap *
  page47_i16
#ISCELL
  mstr_standard tap *
  page47_i160
#ISCELL
  mstr_standard tap *
  page47_i161
#ISCELL
  mstr_standard tap *
  page47_i162
#ISCELL
  mstr_standard tap *
  page47_i17
#ISCELL
  mstr_standard tap *
  page47_i174
#ISCELL
  mstr_standard tap *
  page47_i175
#ISCELL
  mstr_standard offpage *
  page47_i177
#ISCELL
  mstr_standard offpage *
  page47_i178
#CELL
  mstr_sconn sconn288_h44441004 *
  page47_i179
#ISCELL
  mstr_standard tap *
  page47_i18
#ISCELL
  mstr_symbols gnd *
  page47_i180
#ISCELL
  mstr_standard offpage *
  page47_i183
#ISCELL
  mstr_symbols gnd *
  page47_i184
#ISCELL
  mstr_standard offpage *
  page47_i186
#ISCELL
  mstr_standard offpage *
  page47_i187
#CELL
  dev_discrete cap_a *
  page47_i188
#ISCELL
  mstr_symbols gnd *
  page47_i189
#ISCELL
  mstr_standard tap *
  page47_i19
#ISCELL
  mstr_symbols pvpp_abc *
  page47_i190
#ISCELL
  mstr_symbols pvpp_abc *
  page47_i191
#ISCELL
  mstr_standard offpage *
  page47_i192
#ISCELL
  mstr_standard tap *
  page47_i196
#ISCELL
  mstr_standard tap *
  page47_i197
#ISCELL
  mstr_symbols p12v_nvdimm_abc *
  page47_i198
#ISCELL
  mstr_standard offpage *
  page47_i2
#ISCELL
  mstr_standard tap *
  page47_i20
#ISCELL
  mstr_standard tap *
  page47_i21
#ISCELL
  mstr_standard tap *
  page47_i22
#ISCELL
  mstr_standard tap *
  page47_i23
#ISCELL
  mstr_standard tap *
  page47_i24
#ISCELL
  mstr_standard tap *
  page47_i25
#ISCELL
  mstr_standard tap *
  page47_i26
#ISCELL
  mstr_standard tap *
  page47_i27
#ISCELL
  mstr_standard tap *
  page47_i28
#ISCELL
  mstr_standard tap *
  page47_i29
#ISCELL
  mstr_standard tap *
  page47_i3
#ISCELL
  mstr_standard tap *
  page47_i30
#ISCELL
  mstr_standard tap *
  page47_i31
#ISCELL
  mstr_standard tap *
  page47_i32
#ISCELL
  mstr_standard tap *
  page47_i33
#ISCELL
  mstr_standard tap *
  page47_i34
#ISCELL
  mstr_standard tap *
  page47_i35
#ISCELL
  mstr_standard tap *
  page47_i36
#ISCELL
  mstr_standard tap *
  page47_i37
#ISCELL
  mstr_standard tap *
  page47_i38
#ISCELL
  mstr_standard tap *
  page47_i39
#ISCELL
  mstr_standard tap *
  page47_i4
#ISCELL
  mstr_standard tap *
  page47_i40
#ISCELL
  mstr_standard tap *
  page47_i41
#CELL
  mstr_sconn sconn288_h44441004 *
  page47_i43
#ISCELL
  mstr_symbols gnd *
  page47_i44
#ISCELL
  mstr_standard offpage *
  page47_i45
#ISCELL
  mstr_standard tap *
  page47_i46
#ISCELL
  mstr_standard tap *
  page47_i47
#ISCELL
  mstr_standard tap *
  page47_i48
#ISCELL
  mstr_standard tap *
  page47_i49
#ISCELL
  mstr_standard tap *
  page47_i5
#ISCELL
  mstr_standard tap *
  page47_i50
#ISCELL
  mstr_standard tap *
  page47_i51
#ISCELL
  mstr_standard tap *
  page47_i52
#ISCELL
  mstr_standard tap *
  page47_i53
#ISCELL
  mstr_standard tap *
  page47_i54
#ISCELL
  mstr_standard tap *
  page47_i55
#ISCELL
  mstr_standard tap *
  page47_i56
#ISCELL
  mstr_standard tap *
  page47_i57
#ISCELL
  mstr_standard tap *
  page47_i58
#ISCELL
  mstr_standard tap *
  page47_i59
#ISCELL
  mstr_standard tap *
  page47_i6
#ISCELL
  mstr_standard tap *
  page47_i60
#CELL
  mstr_sconn sconn288_h44441004 *
  page47_i61
#ISCELL
  mstr_standard tap *
  page47_i62
#ISCELL
  mstr_standard tap *
  page47_i63
#ISCELL
  mstr_standard tap *
  page47_i64
#ISCELL
  mstr_standard tap *
  page47_i65
#ISCELL
  mstr_standard tap *
  page47_i66
#ISCELL
  mstr_standard tap *
  page47_i67
#ISCELL
  mstr_standard tap *
  page47_i68
#ISCELL
  mstr_standard tap *
  page47_i69
#ISCELL
  mstr_standard tap *
  page47_i7
#ISCELL
  mstr_standard tap *
  page47_i70
#ISCELL
  mstr_standard tap *
  page47_i71
#ISCELL
  mstr_standard tap *
  page47_i72
#ISCELL
  mstr_standard tap *
  page47_i73
#ISCELL
  mstr_standard tap *
  page47_i74
#ISCELL
  mstr_standard tap *
  page47_i75
#ISCELL
  mstr_standard tap *
  page47_i76
#ISCELL
  mstr_standard tap *
  page47_i77
#ISCELL
  mstr_standard tap *
  page47_i78
#ISCELL
  mstr_standard tap *
  page47_i79
#ISCELL
  mstr_standard tap *
  page47_i8
#ISCELL
  mstr_standard tap *
  page47_i80
#ISCELL
  mstr_standard tap *
  page47_i81
#ISCELL
  mstr_standard tap *
  page47_i82
#ISCELL
  mstr_standard tap *
  page47_i83
#ISCELL
  mstr_standard tap *
  page47_i84
#ISCELL
  mstr_standard tap *
  page47_i85
#ISCELL
  mstr_standard tap *
  page47_i86
#ISCELL
  mstr_standard tap *
  page47_i87
#ISCELL
  mstr_standard tap *
  page47_i88
#ISCELL
  mstr_standard tap *
  page47_i89
#ISCELL
  mstr_standard tap *
  page47_i9
#ISCELL
  mstr_standard tap *
  page47_i90
#ISCELL
  mstr_standard tap *
  page47_i91
#ISCELL
  mstr_standard tap *
  page47_i92
#ISCELL
  mstr_standard tap *
  page47_i93
#ISCELL
  mstr_standard tap *
  page47_i94
#ISCELL
  mstr_standard tap *
  page47_i95
#ISCELL
  mstr_standard tap *
  page47_i96
#ISCELL
  mstr_standard tap *
  page47_i97
#ISCELL
  mstr_standard tap *
  page47_i98
#ISCELL
  mstr_standard tap *
  page47_i99
